# T6G (Grand Teton) — schematic netlist excerpt (pin names and nets, part order shuffled) for the footprints in the layout excerpt that follows; sources: Cadence DE-HDL packaged netlist, KiCad conversion of 04192023_DAF0TMB3IC0_F0TG_MB_C_brd_V02_OCP.brd

C121  Q_CAP  4.7UF 6.3V 20% X6S  pkg 0402  page 323 : A = P1V8_CPU1_RT0_1A ; B = GND
C529  Q_CAP  1UF 4V 20% X6S  pkg 0201  page 279 : A = P0V9_CPU0_RT0_2A ; B = GND
C2306  Q_CAP  22UF 4V 20% X6S  pkg C0402  page 73 : A = PVDDCR_CPU0_P1 ; B = GND

(kicad_pcb
	(version 20260206)
	(generator "pcbnew")
	(generator_version "10.0")
	(general
		(thickness 1.6)
		(legacy_teardrops no)
	)
	(paper "A4")
	(title_block
		(title "04192023_DAF0TMB3IC0_F0TG_MB_C_brd_V02_OCP.brd")
		(comment 1 "Grand Teton / footprints 6046-6048 of 8354")
	)
	(layers
		(0 "F.Cu" signal "TOP")
		(4 "In1.Cu" signal "GND")
		(6 "In2.Cu" signal "IN1")
		(8 "In3.Cu" signal "GND1")
		(10 "In4.Cu" signal "IN2")
		(12 "In5.Cu" signal "GND2")
		(14 "In6.Cu" signal "IN3")
		(16 "In7.Cu" signal "GND3")
		(18 "In8.Cu" signal "VCC")
		(20 "In9.Cu" signal "VCC1")
		(22 "In10.Cu" signal "GND4")
		(24 "In11.Cu" signal "IN4")
		(26 "In12.Cu" signal "GND5")
		(28 "In13.Cu" signal "IN5")
		(30 "In14.Cu" signal "GND6")
		(32 "In15.Cu" signal "IN6")
		(34 "In16.Cu" signal "GND7")
		(2 "B.Cu" signal "BOTTOM")
		(9 "F.Adhes" user "F.Adhesive")
		(11 "B.Adhes" user "B.Adhesive")
		(13 "F.Paste" user "Package Geometry/Pastemask Top")
		(15 "B.Paste" user "Package Geometry/Pastemask Bottom")
		(5 "F.SilkS" user "Ref Des/Silkscreen Top")
		(7 "B.SilkS" user "Ref Des/Silkscreen Bottom")
		(1 "F.Mask" user "Board Geometry/Soldermask Top")
		(3 "B.Mask" user "Board Geometry/Soldermask Bottom")
		(17 "Dwgs.User" user "User.Drawings")
		(19 "Cmts.User" user "User.Comments")
		(21 "Eco1.User" user "User.Eco1")
		(23 "Eco2.User" user "User.Eco2")
		(25 "Edge.Cuts" user "Board Geometry/Outline")
		(27 "Margin" user)
		(31 "F.CrtYd" user "Package Geometry/Place Bound Top")
		(29 "B.CrtYd" user "Package Geometry/Place Bound Bottom")
		(35 "F.Fab" user "Ref Des/Assembly Top")
		(33 "B.Fab" user "Ref Des/Assembly Bottom")
	)
	(footprint ""
		(layer "B.Cu")
		(at 55.791354 -390.560052 90)
		(property "Reference" "C121"
			(at 0 0 90)
			(layer "B.SilkS")
			(hide yes)
			(effects
				(font
					(size 1.27 1.27)
				)
				(justify mirror)
			)
		)
		(property "Value" ""
			(at 0 0 90)
			(layer "B.Fab")
			(effects
				(font
					(size 1.27 1.27)
				)
				(justify mirror)
			)
		)
		(duplicate_pad_numbers_are_jumpers no)
		(fp_line
			(start 0.7874 -0.4064)
			(end -0.7874 -0.4064)
			(stroke
				(width 0.1524)
				(type default)
			)
			(layer "B.SilkS")
		)
		(fp_line
			(start -0.7874 -0.4064)
			(end -0.7874 0.4064)
			(stroke
				(width 0.1524)
				(type default)
			)
			(layer "B.SilkS")
		)
		(fp_line
			(start 0.7874 0.4064)
			(end 0.7874 -0.4064)
			(stroke
				(width 0.1524)
				(type default)
			)
			(layer "B.SilkS")
		)
		(fp_line
			(start -0.7874 0.4064)
			(end 0.7874 0.4064)
			(stroke
				(width 0.1524)
				(type default)
			)
			(layer "B.SilkS")
		)
		(fp_line
			(start 0.67945 -0.305054)
			(end 0.12065 -0.305054)
			(stroke
				(width 0.1)
				(type default)
			)
			(layer "B.Fab")
		)
		(fp_line
			(start 0.12065 -0.305054)
			(end 0.12065 -0.2794)
			(stroke
				(width 0.1)
				(type default)
			)
			(layer "B.Fab")
		)
		(fp_line
			(start -0.12065 -0.3048)
			(end -0.67945 -0.3048)
			(stroke
				(width 0.1)
				(type default)
			)
			(layer "B.Fab")
		)
		(fp_line
			(start -0.67945 -0.3048)
			(end -0.67945 0.3048)
			(stroke
				(width 0.1)
				(type default)
			)
			(layer "B.Fab")
		)
		(fp_line
			(start 0.12065 -0.2794)
			(end -0.12065 -0.2794)
			(stroke
				(width 0.1)
				(type default)
			)
			(layer "B.Fab")
		)
		(fp_line
			(start -0.12065 -0.2794)
			(end -0.12065 -0.3048)
			(stroke
				(width 0.1)
				(type default)
			)
			(layer "B.Fab")
		)
		(fp_line
			(start 0.12065 0.2794)
			(end 0.12065 0.3048)
			(stroke
				(width 0.1)
				(type default)
			)
			(layer "B.Fab")
		)
		(fp_line
			(start -0.120396 0.2794)
			(end 0.12065 0.2794)
			(stroke
				(width 0.1)
				(type default)
			)
			(layer "B.Fab")
		)
		(fp_line
			(start 0.67945 0.3048)
			(end 0.67945 -0.305054)
			(stroke
				(width 0.1)
				(type default)
			)
			(layer "B.Fab")
		)
		(fp_line
			(start 0.12065 0.3048)
			(end 0.67945 0.3048)
			(stroke
				(width 0.1)
				(type default)
			)
			(layer "B.Fab")
		)
		(fp_line
			(start -0.120396 0.3048)
			(end -0.120396 0.2794)
			(stroke
				(width 0.1)
				(type default)
			)
			(layer "B.Fab")
		)
		(fp_line
			(start -0.67945 0.3048)
			(end -0.120396 0.3048)
			(stroke
				(width 0.1)
				(type default)
			)
			(layer "B.Fab")
		)
		(pad "1" smd circle
			(at 0.40005 0 270)
			(size 0 0)
			(layers "B.Cu" "B.Mask" "B.Paste")
			(net "P1V8_CPU1_RT0_1A")
		)
		(pad "2" smd circle
			(at -0.40005 0 270)
			(size 0 0)
			(layers "B.Cu" "B.Mask" "B.Paste")
			(net "GND")
		)
	)
	(footprint ""
		(layer "B.Cu")
		(at 317.778384 -395.148562 90)
		(property "Reference" "C529"
			(at 0 0 90)
			(layer "B.SilkS")
			(hide yes)
			(effects
				(font
					(size 1.27 1.27)
				)
				(justify mirror)
			)
		)
		(property "Value" ""
			(at 0 0 90)
			(layer "B.Fab")
			(effects
				(font
					(size 1.27 1.27)
				)
				(justify mirror)
			)
		)
		(duplicate_pad_numbers_are_jumpers no)
		(fp_line
			(start 0.299974 -0.150114)
			(end -0.299974 -0.150114)
			(stroke
				(width 0.1)
				(type default)
			)
			(layer "B.Fab")
		)
		(fp_line
			(start -0.299974 -0.150114)
			(end -0.299974 0.150114)
			(stroke
				(width 0.1)
				(type default)
			)
			(layer "B.Fab")
		)
		(fp_line
			(start 0.299974 0.150114)
			(end 0.299974 -0.150114)
			(stroke
				(width 0.1)
				(type default)
			)
			(layer "B.Fab")
		)
		(fp_line
			(start -0.299974 0.150114)
			(end 0.299974 0.150114)
			(stroke
				(width 0.1)
				(type default)
			)
			(layer "B.Fab")
		)
		(pad "1" smd rect
			(at 0.2667 0 270)
			(size 0.3048 0.381)
			(layers "B.Cu" "B.Mask" "B.Paste")
			(net "P0V9_CPU0_RT0_2A")
		)
		(pad "2" smd rect
			(at -0.2667 0 270)
			(size 0.3048 0.381)
			(layers "B.Cu" "B.Mask" "B.Paste")
			(net "GND")
		)
	)
	(footprint ""
		(layer "B.Cu")
		(at 116.527834 -245.487952)
		(property "Reference" "C2306"
			(at 0 0 0)
			(layer "B.SilkS")
			(hide yes)
			(effects
				(font
					(size 1.27 1.27)
				)
				(justify mirror)
			)
		)
		(property "Value" ""
			(at 0 0 0)
			(layer "B.Fab")
			(effects
				(font
					(size 1.27 1.27)
				)
				(justify mirror)
			)
		)
		(duplicate_pad_numbers_are_jumpers no)
		(fp_line
			(start -0.7874 -0.4064)
			(end -0.7874 0.4064)
			(stroke
				(width 0.1524)
				(type default)
			)
			(layer "B.SilkS")
		)
		(fp_line
			(start -0.7874 0.4064)
			(end 0.7874 0.4064)
			(stroke
				(width 0.1524)
				(type default)
			)
			(layer "B.SilkS")
		)
		(fp_line
			(start 0.7874 -0.4064)
			(end -0.7874 -0.4064)
			(stroke
				(width 0.1524)
				(type default)
			)
			(layer "B.SilkS")
		)
		(fp_line
			(start 0.7874 0.4064)
			(end 0.7874 -0.4064)
			(stroke
				(width 0.1524)
				(type default)
			)
			(layer "B.SilkS")
		)
		(fp_line
			(start -0.67945 -0.3048)
			(end -0.67945 0.3048)
			(stroke
				(width 0.1)
				(type default)
			)
			(layer "B.Fab")
		)
		(fp_line
			(start -0.67945 0.3048)
			(end -0.120396 0.3048)
			(stroke
				(width 0.1)
				(type default)
			)
			(layer "B.Fab")
		)
		(fp_line
			(start -0.12065 -0.3048)
			(end -0.67945 -0.3048)
			(stroke
				(width 0.1)
				(type default)
			)
			(layer "B.Fab")
		)
		(fp_line
			(start -0.12065 -0.2794)
			(end -0.12065 -0.3048)
			(stroke
				(width 0.1)
				(type default)
			)
			(layer "B.Fab")
		)
		(fp_line
			(start -0.120396 0.2794)
			(end 0.12065 0.2794)
			(stroke
				(width 0.1)
				(type default)
			)
			(layer "B.Fab")
		)
		(fp_line
			(start -0.120396 0.3048)
			(end -0.120396 0.2794)
			(stroke
				(width 0.1)
				(type default)
			)
			(layer "B.Fab")
		)
		(fp_line
			(start 0.12065 -0.305054)
			(end 0.12065 -0.2794)
			(stroke
				(width 0.1)
				(type default)
			)
			(layer "B.Fab")
		)
		(fp_line
			(start 0.12065 -0.2794)
			(end -0.12065 -0.2794)
			(stroke
				(width 0.1)
				(type default)
			)
			(layer "B.Fab")
		)
		(fp_line
			(start 0.12065 0.2794)
			(end 0.12065 0.3048)
			(stroke
				(width 0.1)
				(type default)
			)
			(layer "B.Fab")
		)
		(fp_line
			(start 0.12065 0.3048)
			(end 0.67945 0.3048)
			(stroke
				(width 0.1)
				(type default)
			)
			(layer "B.Fab")
		)
		(fp_line
			(start 0.67945 -0.305054)
			(end 0.12065 -0.305054)
			(stroke
				(width 0.1)
				(type default)
			)
			(layer "B.Fab")
		)
		(fp_line
			(start 0.67945 0.3048)
			(end 0.67945 -0.305054)
			(stroke
				(width 0.1)
				(type default)
			)
			(layer "B.Fab")
		)
		(pad "1" smd circle
			(at 0.40005 0 180)
			(size 0 0)
			(layers "B.Cu" "B.Mask" "B.Paste")
			(net "PVDDCR_CPU0_P1")
		)
		(pad "2" smd circle
			(at -0.40005 0 180)
			(size 0 0)
			(layers "B.Cu" "B.Mask" "B.Paste")
			(net "GND")
		)
	)
)
